# BASEBOARD_FAB2 (Tioga Pass) — schematic netlist excerpt (pin names and nets, part order shuffled) for the footprints in the layout excerpt that follows; sources: Cadence DE-HDL packaged netlist, KiCad conversion of Wiwynn_Tioga_Pass_MB.brd

R777  RES  0.0 5% CHIP  pkg 0402  page 244 : A = P3E_CPU0_PE1_PCH_RXP<12> ; B = P3E_CPU0_PE1_PCH_CON_RXP<12>
C9R9  CAPP  470UF 2.5V 20% ALUM  pkg 3018  page 208 : A = PVCCIN_CPU1 ; B = GND

(kicad_pcb
	(version 20260206)
	(generator "pcbnew")
	(generator_version "10.0")
	(general
		(thickness 1.6)
		(legacy_teardrops no)
	)
	(paper "A4")
	(title_block
		(title "Wiwynn_Tioga_Pass_MB.brd")
		(comment 1 "Tioga Pass / footprints 2745-2746 of 4770")
	)
	(layers
		(0 "F.Cu" signal "TOP")
		(4 "In1.Cu" signal "L2GND")
		(6 "In2.Cu" signal "L3")
		(8 "In3.Cu" signal "L4GND")
		(10 "In4.Cu" signal "L5")
		(12 "In5.Cu" signal "L6GND")
		(14 "In6.Cu" signal "L7VCC")
		(16 "In7.Cu" signal "L8VCC")
		(18 "In8.Cu" signal "L9GND")
		(20 "In9.Cu" signal "L10")
		(22 "In10.Cu" signal "L11GND")
		(24 "In11.Cu" signal "L12")
		(26 "In12.Cu" signal "L13GND")
		(2 "B.Cu" signal "BOTTOM")
		(9 "F.Adhes" user "F.Adhesive")
		(11 "B.Adhes" user "B.Adhesive")
		(13 "F.Paste" user "Package Geometry/Pastemask Top")
		(15 "B.Paste" user "Package Geometry/Pastemask Bottom")
		(5 "F.SilkS" user "Ref Des/Silkscreen Top")
		(7 "B.SilkS" user "Ref Des/Silkscreen Bottom")
		(1 "F.Mask" user "Board Geometry/Soldermask Top")
		(3 "B.Mask" user "Board Geometry/Soldermask Bottom")
		(17 "Dwgs.User" user "User.Drawings")
		(19 "Cmts.User" user "User.Comments")
		(21 "Eco1.User" user "User.Eco1")
		(23 "Eco2.User" user "User.Eco2")
		(25 "Edge.Cuts" user "Board Geometry/Outline")
		(27 "Margin" user)
		(31 "F.CrtYd" user "Package Geometry/Place Bound Top")
		(29 "B.CrtYd" user "Package Geometry/Place Bound Bottom")
		(35 "F.Fab" user "Ref Des/Assembly Top")
		(33 "B.Fab" user "Ref Des/Assembly Bottom")
	)
	(footprint ""
		(layer "B.Cu")
		(at 353.654614 -122.662442 -90)
		(property "Reference" "R777"
			(at 0.8382 -0.67818 270)
			(unlocked yes)
			(layer "B.SilkS")
			(effects
				(font
					(size 0.4064 0.254)
					(thickness 0.1524)
				)
				(justify left mirror)
			)
		)
		(property "Value" ""
			(at 0 0 90)
			(layer "B.Fab")
			(effects
				(font
					(size 1.27 1.27)
				)
				(justify mirror)
			)
		)
		(duplicate_pad_numbers_are_jumpers no)
		(fp_poly
			(pts
				(xy 0.2794 -0.1016) (xy -0.2794 -0.1016) (xy -0.2794 0.9906) (xy 0.2794 0.9906)
			)
			(stroke
				(width 0)
				(type default)
			)
			(fill no)
			(layer "B.CrtYd")
		)
		(fp_line
			(start -0.2794 0.9906)
			(end -0.2794 -0.1016)
			(stroke
				(width 0.1)
				(type default)
			)
			(layer "B.Fab")
		)
		(fp_line
			(start 0.2794 0.9906)
			(end -0.2794 0.9906)
			(stroke
				(width 0.1)
				(type default)
			)
			(layer "B.Fab")
		)
		(fp_line
			(start -0.2794 -0.1016)
			(end 0.2794 -0.1016)
			(stroke
				(width 0.1)
				(type default)
			)
			(layer "B.Fab")
		)
		(fp_line
			(start 0.2794 -0.1016)
			(end 0.2794 0.9906)
			(stroke
				(width 0.1)
				(type default)
			)
			(layer "B.Fab")
		)
		(pad "1" smd rect
			(at 0 0 90)
			(size 0.508 0.508)
			(layers "B.Cu" "B.Mask" "B.Paste")
			(net "P3E_CPU0_PE1_PCH_RXP<12>")
		)
		(pad "2" smd rect
			(at 0 0.889 90)
			(size 0.508 0.508)
			(layers "B.Cu" "B.Mask" "B.Paste")
			(net "P3E_CPU0_PE1_PCH_CON_RXP<12>")
		)
		(zone
			(layer "B.Cu")
			(hatch none 0.5)
			(connect_pads
				(clearance 0)
			)
			(min_thickness 0.25)
			(keepout
				(tracks not_allowed)
				(vias allowed)
				(pads allowed)
				(copperpour not_allowed)
				(footprints allowed)
			)
			(placement
				(enabled no)
				(sheetname "")
			)
			(fill
				(thermal_gap 0.5)
				(thermal_bridge_width 0.5)
				(island_removal_mode 0)
			)
			(polygon
				(pts
					(xy 353.019614 -122.408442) (xy 353.019614 -122.916442) (xy 353.400614 -122.916442) (xy 353.400614 -122.408442)
				)
			)
		)
		(zone
			(layer "B.Cu")
			(hatch none 0.5)
			(connect_pads
				(clearance 0)
			)
			(min_thickness 0.25)
			(keepout
				(tracks allowed)
				(vias not_allowed)
				(pads allowed)
				(copperpour not_allowed)
				(footprints allowed)
			)
			(placement
				(enabled no)
				(sheetname "")
			)
			(fill
				(thermal_gap 0.5)
				(thermal_bridge_width 0.5)
				(island_removal_mode 0)
			)
			(polygon
				(pts
					(xy 353.400614 -122.408442) (xy 353.400614 -122.916442) (xy 353.019614 -122.916442) (xy 353.019614 -122.408442)
				)
			)
		)
	)
	(footprint ""
		(layer "B.Cu")
		(at 45.212 -57.023 -90)
		(property "Reference" "C9R9"
			(at 0.15367 -3.556 0)
			(unlocked yes)
			(layer "B.SilkS")
			(effects
				(font
					(size 0.7874 0.5842)
					(thickness 0.1524)
				)
				(justify mirror)
			)
		)
		(property "Value" ""
			(at 0 0 90)
			(layer "B.Fab")
			(effects
				(font
					(size 1.27 1.27)
				)
				(justify mirror)
			)
		)
		(duplicate_pad_numbers_are_jumpers no)
		(fp_line
			(start -2.286 7.366)
			(end -1.600708 7.366)
			(stroke
				(width 0.1524)
				(type default)
			)
			(layer "B.SilkS")
		)
		(fp_line
			(start -2.286 7.366)
			(end -2.286 1.63195)
			(stroke
				(width 0.1524)
				(type default)
			)
			(layer "B.SilkS")
		)
		(fp_line
			(start 2.286 7.366)
			(end 1.60147 7.366)
			(stroke
				(width 0.1524)
				(type default)
			)
			(layer "B.SilkS")
		)
		(fp_line
			(start 2.286 7.366)
			(end 2.286 1.632712)
			(stroke
				(width 0.1524)
				(type default)
			)
			(layer "B.SilkS")
		)
		(fp_line
			(start -2.504948 1.633728)
			(end -1.6002 1.633728)
			(stroke
				(width 0.1524)
				(type default)
			)
			(layer "B.SilkS")
		)
		(fp_line
			(start 2.563114 1.633728)
			(end 1.6002 1.633728)
			(stroke
				(width 0.1524)
				(type default)
			)
			(layer "B.SilkS")
		)
		(fp_line
			(start -2.504948 -1.616456)
			(end -2.504948 1.633728)
			(stroke
				(width 0.1524)
				(type default)
			)
			(layer "B.SilkS")
		)
		(fp_line
			(start -1.6002 -1.616456)
			(end -2.504948 -1.616456)
			(stroke
				(width 0.1524)
				(type default)
			)
			(layer "B.SilkS")
		)
		(fp_line
			(start 1.6002 -1.616456)
			(end 2.563114 -1.616456)
			(stroke
				(width 0.1524)
				(type default)
			)
			(layer "B.SilkS")
		)
		(fp_line
			(start 2.563114 -1.616456)
			(end 2.563114 1.633728)
			(stroke
				(width 0.1524)
				(type default)
			)
			(layer "B.SilkS")
		)
		(fp_rect
			(start 2.286 7.366)
			(end -2.286 -0.254)
			(stroke
				(width 0)
				(type default)
			)
			(fill no)
			(layer "B.CrtYd")
		)
		(fp_line
			(start -2.286 7.366)
			(end 2.286 7.366)
			(stroke
				(width 0.1)
				(type default)
			)
			(layer "B.Fab")
		)
		(fp_line
			(start 2.286 7.366)
			(end 2.286 -0.254)
			(stroke
				(width 0.1)
				(type default)
			)
			(layer "B.Fab")
		)
		(fp_line
			(start -2.286 -0.254)
			(end -2.286 7.366)
			(stroke
				(width 0.1)
				(type default)
			)
			(layer "B.Fab")
		)
		(fp_line
			(start 2.286 -0.254)
			(end -2.286 -0.254)
			(stroke
				(width 0.1)
				(type default)
			)
			(layer "B.Fab")
		)
		(pad "1" smd rect
			(at 0 0 90)
			(size 2.54 3.048)
			(layers "B.Cu" "B.Mask" "B.Paste")
			(net "PVCCIN_CPU1")
		)
		(pad "2" smd rect
			(at 0 7.112 90)
			(size 2.54 3.048)
			(layers "B.Cu" "B.Mask" "B.Paste")
			(net "GND")
		)
	)
)
